<?xml version="1.0" encoding="UTF-8" standalone="no"?><root><attribute Name="MATERIAL" Description=" "><value Kind="Property"><data Type="Scalar" Storage="String"/><flags><s>Package</s></flags></value><objects><valid><o>System</o><o>Design</o><o>PartDefn</o><o>Part</o><o>GateDefn</o><o>Gate</o><o>DesignInstance</o></valid><noInherit><pair Kind1="Gate" Kind2="Pin"/></noInherit></objects></attribute><attribute Name="TOLERANCE" Description=" "><value Kind="Property"><data Type="Scalar" Storage="String"/><flags><s>Package</s></flags></value><objects><valid><o>System</o><o>Design</o><o>PartDefn</o><o>Part</o><o>GateDefn</o><o>Gate</o><o>DesignInstance</o></valid><noInherit><pair Kind1="Gate" Kind2="Pin"/></noInherit></objects></attribute><attribute Name="WATTAGE" Description=" "><value Kind="Property"><data Type="Scalar" Storage="String"/><flags><s>Package</s></flags></value><objects><valid><o>System</o><o>Design</o><o>PartDefn</o><o>Part</o><o>GateDefn</o><o>Gate</o><o>DesignInstance</o></valid><noInherit><pair Kind1="Gate" Kind2="Pin"/></noInherit></objects></attribute><attribute Name="CDS_LMAN_SYM_OUTLINE" Description=" "><value Kind="Property"><data Type="Scalar" Storage="String"/><flags><s>Package</s></flags></value><objects><valid><o>System</o><o>Design</o><o>PartDefn</o><o>Part</o><o>GateDefn</o><o>Gate</o><o>DesignInstance</o></valid><noInherit><pair Kind1="Gate" Kind2="Pin"/></noInherit></objects></attribute><attribute Name="PART_TYPE" Description=" "><value Kind="Property"><data Type="Scalar" Storage="String"/><flags><s>Package</s></flags></value><objects><valid><o>System</o><o>Design</o><o>PartDefn</o><o>Part</o><o>GateDefn</o><o>Gate</o><o>DesignInstance</o></valid><noInherit><pair Kind1="Gate" Kind2="Pin"/></noInherit></objects></attribute><attribute Name="SEC_TYPE" Description=" "><value Kind="Property"><data Type="Scalar" Storage="String"/><flags><s>Package</s></flags></value><objects><valid><o>System</o><o>Design</o><o>PartDefn</o><o>Part</o><o>GateDefn</o><o>Gate</o><o>DesignInstance</o></valid><noInherit><pair Kind1="Gate" Kind2="Pin"/></noInherit></objects></attribute><attribute Name="MANUF_PN" Description=" "><value Kind="Property"><data Type="Scalar" Storage="String"/><flags><s>Package</s></flags></value><objects><valid><o>System</o><o>Design</o><o>PartDefn</o><o>Part</o><o>GateDefn</o><o>Gate</o><o>DesignInstance</o></valid><noInherit><pair Kind1="Gate" Kind2="Pin"/></noInherit></objects></attribute><attribute Name="PIN_NAMES_ROTATE" Description=" "><value Kind="Property"><data Type="Scalar" Storage="String"/><flags><s>Package</s></flags></value><objects><valid><o>System</o><o>Design</o><o>PartDefn</o><o>Part</o><o>GateDefn</o><o>Gate</o><o>DesignInstance</o></valid><noInherit><pair Kind1="Gate" Kind2="Pin"/></noInherit></objects></attribute><attribute Name="PIN_LENGTH" Description=" "><value Kind="Property"><data Type="Scalar" Storage="String"/><flags><s>Package</s></flags></value><objects><valid><o>Pin</o></valid><noInherit><pair Kind1="Gate" Kind2="Pin"/></noInherit></objects></attribute><attribute Name="COLOR" Description=" "><value Kind="Property"><data Type="Scalar" Storage="String"/><flags><s>Package</s></flags></value><objects><valid><o>System</o><o>Design</o><o>PartDefn</o><o>Part</o><o>GateDefn</o><o>Gate</o><o>DesignInstance</o></valid><noInherit><pair Kind1="Gate" Kind2="Pin"/></noInherit></objects></attribute><attribute Name="CURRENT_AMP" Description=" "><value Kind="Property"><data Type="Scalar" Storage="String"/><flags><s>Package</s></flags></value><objects><valid><o>System</o><o>Design</o><o>PartDefn</o><o>Part</o><o>GateDefn</o><o>Gate</o><o>DesignInstance</o></valid><noInherit><pair Kind1="Gate" Kind2="Pin"/></noInherit></objects></attribute><attribute Name="BOM_COST" Description=" "><value Kind="Property"><data Type="Scalar" Storage="String"/><flags><s>Package</s></flags></value><objects><valid><o>System</o><o>Design</o><o>PartDefn</o><o>Part</o><o>GateDefn</o><o>Gate</o><o>DesignInstance</o></valid><noInherit><pair Kind1="Gate" Kind2="Pin"/></noInherit></objects></attribute><attribute Name="OSCON" Description=" "><value Kind="Property"><data Type="Scalar" Storage="String"/><flags><s>Package</s></flags></value><objects><valid><o>System</o><o>Design</o><o>PartDefn</o><o>Part</o><o>GateDefn</o><o>Gate</o><o>DesignInstance</o></valid><noInherit><pair Kind1="Gate" Kind2="Pin"/></noInherit></objects></attribute><attribute Name="L1" Description=" "><value Kind="Property"><data Type="Scalar" Storage="String"/><flags><s>Package</s></flags></value><objects><valid><o>System</o><o>Design</o><o>PartDefn</o><o>Part</o><o>GateDefn</o><o>Gate</o><o>DesignInstance</o></valid><noInherit><pair Kind1="Gate" Kind2="Pin"/></noInherit></objects></attribute><attribute Name="PIN_TEXT_VISIBLE" Description=" "><value Kind="Property"><data Type="Scalar" Storage="String"/><flags><s>Package</s></flags></value><objects><valid><o>System</o><o>Design</o><o>PartDefn</o><o>Part</o><o>GateDefn</o><o>Gate</o><o>DesignInstance</o></valid><noInherit><pair Kind1="Gate" Kind2="Pin"/></noInherit></objects></attribute><attribute Name="QPN" Description=" "><value Kind="Property"><data Type="Scalar" Storage="String"/><flags><s>Package</s></flags></value><objects><valid><o>System</o><o>Design</o><o>PartDefn</o><o>Part</o><o>GateDefn</o><o>Gate</o><o>DesignInstance</o></valid><noInherit><pair Kind1="Gate" Kind2="Pin"/></noInherit></objects></attribute></root>